(kicad_pcb
	(version 20241229)
	(generator "pcbnew")
	(generator_version "9.0")
	(general
		(thickness 1.6)
		(legacy_teardrops no)
	)
	(paper "A4")
	(title_block
		(title "GMSL Deserializer")
		(date "2025-10-09")
		(rev "1.0.4")
		(company "Antmicro Ltd")
		(comment 1 "www.antmicro.com")
		(comment 9 "footprints 96-101 of 235")
	)
	(layers
		(0 "F.Cu" signal)
		(4 "In1.Cu" power)
		(6 "In2.Cu" power)
		(2 "B.Cu" signal)
		(9 "F.Adhes" user "F.Adhesive")
		(11 "B.Adhes" user "B.Adhesive")
		(13 "F.Paste" user)
		(15 "B.Paste" user)
		(5 "F.SilkS" user "F.Silkscreen")
		(7 "B.SilkS" user "B.Silkscreen")
		(1 "F.Mask" user)
		(3 "B.Mask" user)
		(17 "Dwgs.User" user "User.Drawings")
		(19 "Cmts.User" user "User.Comments")
		(21 "Eco1.User" user "User.Eco1")
		(23 "Eco2.User" user "User.Eco2")
		(25 "Edge.Cuts" user)
		(27 "Margin" user)
		(31 "F.CrtYd" user "F.Courtyard")
		(29 "B.CrtYd" user "B.Courtyard")
		(35 "F.Fab" user)
		(33 "B.Fab" user)
	)
	(footprint "antmicro-footprints:R_0402_1005Metric"
		(layer "F.Cu")
		(at 177.8 58.674 180)
		(descr "Resistor SMD 0402")
		(tags "resistor SMD 0402")
		(property "Reference" "R23"
			(at 0.718006 -0.408082 0)
			(layer "F.SilkS")
			(effects
				(font
					(size 0.7 0.7)
					(thickness 0.15)
				)
				(justify right bottom)
			)
		)
		(property "Value" "R_1M_0402"
			(at -1.011843 1.772047 0)
			(layer "F.Fab")
			(effects
				(font
					(size 0.7 0.7)
					(thickness 0.15)
				)
				(justify right bottom)
			)
		)
		(property "Datasheet" "https://www.bourns.com/docs/product-datasheets/cr.pdf"
			(at 0 0 180)
			(layer "F.Fab")
			(hide yes)
			(effects
				(font
					(size 1.27 1.27)
					(thickness 0.15)
				)
			)
		)
		(property "Description" "SMD Chip Resistor, 1 Mohm, ± 1%, 62.5 mW, 0402 [1005 Metric], Thick Film, General Purpose"
			(at 0 0 180)
			(layer "F.Fab")
			(hide yes)
			(effects
				(font
					(size 1.27 1.27)
					(thickness 0.15)
				)
			)
		)
		(property "Author" "Antmicro"
			(at 355.6 117.348 0)
			(layer "F.Fab")
			(hide yes)
			(effects
				(font
					(size 1 1)
					(thickness 0.15)
				)
			)
		)
		(property "License" "Apache-2.0"
			(at 355.6 117.348 0)
			(layer "F.Fab")
			(hide yes)
			(effects
				(font
					(size 1 1)
					(thickness 0.15)
				)
			)
		)
		(property "MPN" "CR0402-FX-1004GLF"
			(at 355.6 117.348 0)
			(layer "F.Fab")
			(hide yes)
			(effects
				(font
					(size 1 1)
					(thickness 0.15)
				)
			)
		)
		(property "Manufacturer" "Bourns"
			(at 355.6 117.348 0)
			(layer "F.Fab")
			(hide yes)
			(effects
				(font
					(size 1 1)
					(thickness 0.15)
				)
			)
		)
		(property "Tolerance" "1%"
			(at 355.6 117.348 0)
			(layer "F.Fab")
			(hide yes)
			(effects
				(font
					(size 1 1)
					(thickness 0.15)
				)
			)
		)
		(property "Val" "1M"
			(at 355.6 117.348 0)
			(layer "F.Fab")
			(hide yes)
			(effects
				(font
					(size 1 1)
					(thickness 0.15)
				)
			)
		)
		(sheetname "/Power/")
		(sheetfile "power.kicad_sch")
		(attr smd)
		(fp_rect
			(start -0.925 -0.47)
			(end 0.925 0.47)
			(stroke
				(width 0.05)
				(type default)
			)
			(fill no)
			(layer "F.CrtYd")
		)
		(fp_rect
			(start -0.5 -0.25)
			(end 0.5 0.25)
			(stroke
				(width 0.15)
				(type solid)
			)
			(fill no)
			(layer "F.Fab")
		)
		(pad "1" smd roundrect
			(at -0.48 0 180)
			(size 0.59 0.64)
			(layers "F.Cu" "F.Mask" "F.Paste")
			(roundrect_rratio 0.25)
			(net 1 "GND")
			(pintype "passive")
		)
		(pad "2" smd roundrect
			(at 0.48 0 180)
			(size 0.59 0.64)
			(layers "F.Cu" "F.Mask" "F.Paste")
			(roundrect_rratio 0.25)
			(net 127 "Net-(Q2-G)")
			(pintype "passive")
		)
	)
	(footprint "antmicro-footprints:TP_SMD_0.75mm"
		(layer "F.Cu")
		(at 147.828 97.89)
		(property "Reference" "TP12"
			(at 0 -0.6 0)
			(layer "F.SilkS")
			(hide yes)
			(effects
				(font
					(size 0.7 0.7)
					(thickness 0.15)
				)
				(justify left bottom)
			)
		)
		(property "Value" "TP_0.75mm_SMD"
			(at 0 1.2 0)
			(layer "F.Fab")
			(effects
				(font
					(size 0.7 0.7)
					(thickness 0.15)
				)
				(justify left bottom)
			)
		)
		(property "Description" "SMT test point"
			(at 0 0 0)
			(layer "F.Fab")
			(hide yes)
			(effects
				(font
					(size 1.27 1.27)
					(thickness 0.15)
				)
			)
		)
		(property "Author" "Antmicro"
			(at 0 0 0)
			(layer "F.Fab")
			(hide yes)
			(effects
				(font
					(size 1 1)
					(thickness 0.15)
				)
			)
		)
		(property "License" "Apache-2.0"
			(at 0 0 0)
			(layer "F.Fab")
			(hide yes)
			(effects
				(font
					(size 1 1)
					(thickness 0.15)
				)
			)
		)
		(property "MPN" ""
			(at 0 0 0)
			(layer "F.Fab")
			(hide yes)
			(effects
				(font
					(size 1 1)
					(thickness 0.15)
				)
			)
		)
		(property "Manufacturer" ""
			(at 0 0 0)
			(layer "F.Fab")
			(hide yes)
			(effects
				(font
					(size 1 1)
					(thickness 0.15)
				)
			)
		)
		(sheetname "/Power/")
		(sheetfile "power.kicad_sch")
		(fp_circle
			(center 0 0)
			(end 0.475 0)
			(stroke
				(width 0.05)
				(type default)
			)
			(fill no)
			(layer "F.CrtYd")
		)
		(pad "1" smd circle
			(at 0 0)
			(size 0.75 0.75)
			(layers "F.Cu" "F.Mask")
			(net 123 "/Power/OUT_12V")
			(pinfunction "1")
			(pintype "passive")
		)
	)
	(footprint "antmicro-footprints:L_Coilcraft-PFL1609"
		(layer "F.Cu")
		(at 160.528 53.594)
		(property "Reference" "L12"
			(at -3.162703 0.381344 0)
			(layer "F.SilkS")
			(effects
				(font
					(size 0.7 0.7)
					(thickness 0.15)
				)
				(justify left bottom)
			)
		)
		(property "Value" "L_470n_1A_Coilcraft-PFL1609"
			(at 0 2 0)
			(layer "F.Fab")
			(effects
				(font
					(size 0.7 0.7)
					(thickness 0.15)
				)
				(justify left bottom)
			)
		)
		(property "Datasheet" "https://www.coilcraft.com/getmedia/2f4cd442-d64d-4413-a518-12fcfd03318d/pfl1609.pdf"
			(at 0 0 0)
			(layer "F.Fab")
			(hide yes)
			(effects
				(font
					(size 1.27 1.27)
					(thickness 0.15)
				)
			)
		)
		(property "Description" "Power Inductor (SMT), 6.8 µH, 9.2 A, Shielded, 12.8 A, XAL7070"
			(at 0 0 0)
			(layer "F.Fab")
			(hide yes)
			(effects
				(font
					(size 1.27 1.27)
					(thickness 0.15)
				)
			)
		)
		(property "Author" "Antmicro"
			(at 0 0 0)
			(layer "F.Fab")
			(hide yes)
			(effects
				(font
					(size 1 1)
					(thickness 0.15)
				)
			)
		)
		(property "IMax" "1 A"
			(at 0 0 0)
			(layer "F.Fab")
			(hide yes)
			(effects
				(font
					(size 1 1)
					(thickness 0.15)
				)
			)
		)
		(property "ISat" "0.99 A"
			(at 0 0 0)
			(layer "F.Fab")
			(hide yes)
			(effects
				(font
					(size 1 1)
					(thickness 0.15)
				)
			)
		)
		(property "License" "Apache-2.0"
			(at 0 0 0)
			(layer "F.Fab")
			(hide yes)
			(effects
				(font
					(size 1 1)
					(thickness 0.15)
				)
			)
		)
		(property "MPN" "PFL1609-471"
			(at 0 0 0)
			(layer "F.Fab")
			(hide yes)
			(effects
				(font
					(size 1 1)
					(thickness 0.15)
				)
			)
		)
		(property "Manufacturer" "Coilcraft"
			(at 0 0 0)
			(layer "F.Fab")
			(hide yes)
			(effects
				(font
					(size 1 1)
					(thickness 0.15)
				)
			)
		)
		(property "Size" "1.07x1.8"
			(at 0 0 0)
			(layer "F.Fab")
			(hide yes)
			(effects
				(font
					(size 1 1)
					(thickness 0.15)
				)
			)
		)
		(property "Val" "470n/0.99A"
			(at 0 0 0)
			(layer "F.Fab")
			(hide yes)
			(effects
				(font
					(size 1 1)
					(thickness 0.15)
				)
			)
		)
		(sheetname "/Power/")
		(sheetfile "power.kicad_sch")
		(attr smd)
		(fp_line
			(start -0.23 -0.45)
			(end 0.23 -0.45)
			(stroke
				(width 0.15)
				(type solid)
			)
			(layer "F.SilkS")
		)
		(fp_line
			(start -0.23 0.45)
			(end 0.23 0.45)
			(stroke
				(width 0.15)
				(type solid)
			)
			(layer "F.SilkS")
		)
		(fp_rect
			(start -1.2 -0.84)
			(end 1.2 0.84)
			(stroke
				(width 0.05)
				(type solid)
			)
			(fill no)
			(layer "F.CrtYd")
		)
		(fp_rect
			(start -0.9 -0.535)
			(end 0.9 0.535)
			(stroke
				(width 0.15)
				(type solid)
			)
			(fill no)
			(layer "F.Fab")
		)
		(pad "1" smd roundrect
			(at -0.635 0)
			(size 0.64 1.02)
			(layers "F.Cu" "F.Mask" "F.Paste")
			(roundrect_rratio 0.15)
			(net 58 "Net-(L12-Pad1)")
			(pintype "passive")
		)
		(pad "2" smd roundrect
			(at 0.635 0)
			(size 0.64 1.02)
			(layers "F.Cu" "F.Mask" "F.Paste")
			(roundrect_rratio 0.15)
			(net 62 "Net-(L12-Pad2)")
			(pintype "passive")
		)
	)
	(footprint "antmicro-footprints:TSOT23-6"
		(layer "F.Cu")
		(at 186.364 52.324 -90)
		(property "Reference" "U6"
			(at -2.921 -1.342 180)
			(layer "F.SilkS")
			(effects
				(font
					(size 0.7 0.7)
					(thickness 0.15)
				)
				(justify right bottom)
			)
		)
		(property "Value" "AP22615A_TSOT26"
			(at 0 2.6 90)
			(layer "F.Fab")
			(effects
				(font
					(size 0.7 0.7)
					(thickness 0.15)
				)
				(justify right bottom)
			)
		)
		(property "Datasheet" "https://www.mouser.com/datasheet/2/115/DIOD_S_A0008958405_1-2543193.pdf"
			(at 0 0 270)
			(layer "F.Fab")
			(hide yes)
			(effects
				(font
					(size 1.27 1.27)
					(thickness 0.15)
				)
			)
		)
		(property "Description" "Power Load Distribution Switch, High Side, Active High, 1 Output, 5.5 V, 3.6 A, 0.04 ohm, TSOT-26-6"
			(at 0 0 270)
			(layer "F.Fab")
			(hide yes)
			(effects
				(font
					(size 1.27 1.27)
					(thickness 0.15)
				)
			)
		)
		(property "Author" "Antmicro"
			(at 134.04 238.688 0)
			(layer "F.Fab")
			(hide yes)
			(effects
				(font
					(size 1 1)
					(thickness 0.15)
				)
			)
		)
		(property "License" "Apache-2.0"
			(at 134.04 238.688 0)
			(layer "F.Fab")
			(hide yes)
			(effects
				(font
					(size 1 1)
					(thickness 0.15)
				)
			)
		)
		(property "MPN" "AP22615AWU-7"
			(at 134.04 238.688 0)
			(layer "F.Fab")
			(hide yes)
			(effects
				(font
					(size 1 1)
					(thickness 0.15)
				)
			)
		)
		(property "Manufacturer" "Diodes Incorporated"
			(at 134.04 238.688 0)
			(layer "F.Fab")
			(hide yes)
			(effects
				(font
					(size 1 1)
					(thickness 0.15)
				)
			)
		)
		(sheetname "/Power/")
		(sheetfile "power.kicad_sch")
		(attr smd)
		(fp_line
			(start -1 1.55)
			(end -1 1.4)
			(stroke
				(width 0.15)
				(type solid)
			)
			(layer "F.SilkS")
		)
		(fp_line
			(start 1 1.55)
			(end -1 1.55)
			(stroke
				(width 0.15)
				(type solid)
			)
			(layer "F.SilkS")
		)
		(fp_line
			(start 1 1.55)
			(end 1 1.4)
			(stroke
				(width 0.15)
				(type solid)
			)
			(layer "F.SilkS")
		)
		(fp_line
			(start 1 -1.497)
			(end 1 -1.375)
			(stroke
				(width 0.15)
				(type solid)
			)
			(layer "F.SilkS")
		)
		(fp_line
			(start 1 -1.497)
			(end -1 -1.5)
			(stroke
				(width 0.15)
				(type solid)
			)
			(layer "F.SilkS")
		)
		(fp_line
			(start -1 -1.5)
			(end -1 -1.375)
			(stroke
				(width 0.15)
				(type solid)
			)
			(layer "F.SilkS")
		)
		(fp_circle
			(center -1.44 -1.5)
			(end -1.39 -1.5)
			(stroke
				(width 0.15)
				(type solid)
			)
			(fill yes)
			(layer "F.SilkS")
		)
		(fp_rect
			(start 1.93 -1.7)
			(end -1.93 1.7)
			(stroke
				(width 0.05)
				(type solid)
			)
			(fill no)
			(layer "F.CrtYd")
		)
		(fp_line
			(start -0.45 -1.521)
			(end -0.876 -1.096)
			(stroke
				(width 0.15)
				(type solid)
			)
			(layer "F.Fab")
		)
		(fp_rect
			(start 0.875 1.528)
			(end -0.875 -1.525)
			(stroke
				(width 0.15)
				(type solid)
			)
			(fill no)
			(layer "F.Fab")
		)
		(pad "1" smd rect
			(at -1.301 -0.947 180)
			(size 0.7 1.2)
			(layers "F.Cu" "F.Mask" "F.Paste")
			(net 5 "+5V")
			(pinfunction "OUT")
			(pintype "power_out")
		)
		(pad "2" smd rect
			(at -1.301 0.004 180)
			(size 0.7 1.2)
			(layers "F.Cu" "F.Mask" "F.Paste")
			(net 1 "GND")
			(pinfunction "GND")
			(pintype "power_in")
		)
		(pad "3" smd rect
			(at -1.301 0.954 180)
			(size 0.7 1.2)
			(layers "F.Cu" "F.Mask" "F.Paste")
			(net 72 "/Power/FFC_5V_FLG")
			(pinfunction "FLG")
			(pintype "output")
		)
		(pad "4" smd rect
			(at 1.299 0.954 180)
			(size 0.7 1.2)
			(layers "F.Cu" "F.Mask" "F.Paste")
			(net 63 "/Power/FFC_5V_EN")
			(pinfunction "EN")
			(pintype "input")
		)
		(pad "5" smd rect
			(at 1.299 0.004 180)
			(size 0.7 1.2)
			(layers "F.Cu" "F.Mask" "F.Paste")
			(net 74 "/Power/FFC_5V_ISET")
			(pinfunction "ISET")
			(pintype "passive")
		)
		(pad "6" smd rect
			(at 1.299 -0.947 180)
			(size 0.7 1.2)
			(layers "F.Cu" "F.Mask" "F.Paste")
			(net 113 "/Connectors/FFC_5V")
			(pinfunction "IN")
			(pintype "power_in")
		)
	)
	(footprint "antmicro-footprints:R_0402_1005Metric"
		(layer "F.Cu")
		(at 179.301 50.542)
		(descr "Resistor SMD 0402")
		(tags "resistor SMD 0402")
		(property "Reference" "R16"
			(at 0.775356 0.30709 0)
			(layer "F.SilkS")
			(effects
				(font
					(size 0.7 0.7)
					(thickness 0.15)
				)
				(justify left bottom)
			)
		)
		(property "Value" "R_10k_0402"
			(at -1.011843 1.772047 0)
			(layer "F.Fab")
			(effects
				(font
					(size 0.7 0.7)
					(thickness 0.15)
				)
				(justify left bottom)
			)
		)
		(property "Datasheet" "https://www.bourns.com/docs/product-datasheets/cr.pdf"
			(at 0 0 0)
			(layer "F.Fab")
			(hide yes)
			(effects
				(font
					(size 1.27 1.27)
					(thickness 0.15)
				)
			)
		)
		(property "Description" "SMD Chip Resistor, 10 kohm, ± 1%, 62.5 mW, 0402 [1005 Metric], Thick Film, General Purpose"
			(at 0 0 0)
			(layer "F.Fab")
			(hide yes)
			(effects
				(font
					(size 1.27 1.27)
					(thickness 0.15)
				)
			)
		)
		(property "Author" "Antmicro"
			(at 0 0 0)
			(layer "F.Fab")
			(hide yes)
			(effects
				(font
					(size 1 1)
					(thickness 0.15)
				)
			)
		)
		(property "License" "Apache-2.0"
			(at 0 0 0)
			(layer "F.Fab")
			(hide yes)
			(effects
				(font
					(size 1 1)
					(thickness 0.15)
				)
			)
		)
		(property "MPN" "CR0402-FX-1002GLF"
			(at 0 0 0)
			(layer "F.Fab")
			(hide yes)
			(effects
				(font
					(size 1 1)
					(thickness 0.15)
				)
			)
		)
		(property "Manufacturer" "Bourns"
			(at 0 0 0)
			(layer "F.Fab")
			(hide yes)
			(effects
				(font
					(size 1 1)
					(thickness 0.15)
				)
			)
		)
		(property "Tolerance" "1%"
			(at 0 0 0)
			(layer "F.Fab")
			(hide yes)
			(effects
				(font
					(size 1 1)
					(thickness 0.15)
				)
			)
		)
		(property "Val" "10k"
			(at 0 0 0)
			(layer "F.Fab")
			(hide yes)
			(effects
				(font
					(size 1 1)
					(thickness 0.15)
				)
			)
		)
		(sheetname "/Power/")
		(sheetfile "power.kicad_sch")
		(attr smd)
		(fp_rect
			(start -0.925 -0.47)
			(end 0.925 0.47)
			(stroke
				(width 0.05)
				(type default)
			)
			(fill no)
			(layer "F.CrtYd")
		)
		(fp_rect
			(start -0.5 -0.25)
			(end 0.5 0.25)
			(stroke
				(width 0.15)
				(type solid)
			)
			(fill no)
			(layer "F.Fab")
		)
		(pad "1" smd roundrect
			(at -0.48 0)
			(size 0.59 0.64)
			(layers "F.Cu" "F.Mask" "F.Paste")
			(roundrect_rratio 0.25)
			(net 1 "GND")
			(pintype "passive")
		)
		(pad "2" smd roundrect
			(at 0.48 0)
			(size 0.59 0.64)
			(layers "F.Cu" "F.Mask" "F.Paste")
			(roundrect_rratio 0.25)
			(net 126 "Net-(Q1-G)")
			(pintype "passive")
		)
	)
	(footprint "antmicro-footprints:Conn_FAKRA_7-2287906-0"
		(layer "F.Cu")
		(at 140.784666 38.348)
		(descr "Connector FAKRA, 5 pins")
		(property "Reference" "J3"
			(at 5.054 5.3 0)
			(layer "F.SilkS")
			(effects
				(font
					(size 0.7 0.7)
					(thickness 0.15)
				)
				(justify left bottom)
			)
		)
		(property "Value" "Conn_FAKRA_59S2AQ-40MT5-Z_1"
			(at -6.55 15.019 0)
			(layer "F.Fab")
			(effects
				(font
					(size 0.7 0.7)
					(thickness 0.15)
				)
				(justify left bottom)
			)
		)
		(property ki_fp_filters "*BNC* *SMA* *SMB* *SMC* *Cinch*")
		(sheetname "/Connectors/")
		(sheetfile "connectors.kicad_sch")
		(attr through_hole)
		(fp_line
			(start -4.572 0.94)
			(end -4.572 13.919)
			(stroke
				(width 0.15)
				(type solid)
			)
			(layer "F.SilkS")
		)
		(fp_line
			(start -4.572 13.919)
			(end 4.572 13.919)
			(stroke
				(width 0.15)
				(type solid)
			)
			(layer "F.SilkS")
		)
		(fp_line
			(start 4.572 0.94)
			(end -4.572 0.94)
			(stroke
				(width 0.15)
				(type solid)
			)
			(layer "F.SilkS")
		)
		(fp_line
			(start 4.572 13.919)
			(end 4.572 0.94)
			(stroke
				(width 0.15)
				(type solid)
			)
			(layer "F.SilkS")
		)
		(fp_rect
			(start -5.14 -12.64)
			(end 5.131 14.164)
			(stroke
				(width 0.05)
				(type solid)
			)
			(fill no)
			(layer "F.CrtYd")
		)
		(fp_text user "${REFERENCE}"
			(at -6.55 18.619 0)
			(layer "F.Fab")
			(effects
				(font
					(size 0.7 0.7)
					(thickness 0.15)
				)
				(justify left bottom)
			)
		)
		(fp_text user "Author: Antmicro"
			(at -6.55 17.419 0)
			(layer "F.Fab")
			(effects
				(font
					(size 0.7 0.7)
					(thickness 0.15)
				)
				(justify left bottom)
			)
		)
		(fp_text user "License: Apache-2.0"
			(at -6.55 16.219 0)
			(layer "F.Fab")
			(effects
				(font
					(size 0.7 0.7)
					(thickness 0.15)
				)
				(justify left bottom)
			)
		)
		(pad "1" smd roundrect
			(at 0 3.62 270)
			(size 4.79 1.9)
			(layers "F.Cu" "F.Mask" "F.Paste")
			(roundrect_rratio 0.25)
			(net 115 "/Connectors/PoCB")
			(pinfunction "1")
			(pintype "passive")
		)
		(pad "2" thru_hole circle
			(at -3 3.315 270)
			(size 1.8 1.8)
			(drill 1.45)
			(layers "*.Cu" "*.Mask")
			(remove_unused_layers no)
			(net 1 "GND")
			(pinfunction "2")
			(pintype "passive")
		)
		(pad "2" smd roundrect
			(at -2.9975 3.7175 270)
			(size 4.985 1.8)
			(layers "F.Cu" "F.Mask" "F.Paste")
			(roundrect_rratio 0.25)
			(net 1 "GND")
			(pinfunction "2")
			(pintype "passive")
		)
		(pad "3" thru_hole circle
			(at -3 10.315 270)
			(size 1.8 1.8)
			(drill 1.45)
			(layers "*.Cu" "*.Mask")
			(remove_unused_layers no)
			(net 1 "GND")
			(pinfunction "3")
			(pintype "passive")
		)
		(pad "3" smd roundrect
			(at -3 10.815 270)
			(size 5.6 1.8)
			(layers "F.Cu" "F.Mask" "F.Paste")
			(roundrect_rratio 0.25)
			(net 1 "GND")
			(pinfunction "3")
			(pintype "passive")
		)
		(pad "4" thru_hole circle
			(at 3 10.315 270)
			(size 1.8 1.8)
			(drill 1.45)
			(layers "*.Cu" "*.Mask")
			(remove_unused_layers no)
			(net 1 "GND")
			(pinfunction "4")
			(pintype "passive")
		)
		(pad "4" smd roundrect
			(at 3 10.815 270)
			(size 5.6 1.8)
			(layers "F.Cu" "F.Mask" "F.Paste")
			(roundrect_rratio 0.25)
			(net 1 "GND")
			(pinfunction "4")
			(pintype "passive")
		)
		(pad "5" thru_hole circle
			(at 3 3.315 270)
			(size 1.8 1.8)
			(drill 1.45)
			(layers "*.Cu" "*.Mask")
			(remove_unused_layers no)
			(net 1 "GND")
			(pinfunction "5")
			(pintype "passive")
		)
		(pad "5" smd roundrect
			(at 3 3.72 270)
			(size 4.99 1.8)
			(layers "F.Cu" "F.Mask" "F.Paste")
			(roundrect_rratio 0.25)
			(net 1 "GND")
			(pinfunction "5")
			(pintype "passive")
		)
	)
)
